# T6G (Grand Teton) — schematic netlist excerpt (pin names and nets, part order shuffled) for the footprints in the layout excerpt that follows; sources: Cadence DE-HDL packaged netlist, KiCad conversion of 04192023_DAF0TMB3IC0_F0TG_MB_C_brd_V02_OCP.brd

R2664  Q_RES  33.2 1% CHIP  pkg 0402LF  page 81 : A = FM_GPU_PWRGD_ISO_R ; B = FM_GPU_PWRGD_ISO
R2967  Q_RES  0 5% CHIP  pkg 0402LF  page 250 : A = SMB_PCIE0_3V3AUX_SCL_R3 ; B = SMB_SENSOR_M2_P1_3V3AUX_SCL

(kicad_pcb
	(version 20260206)
	(generator "pcbnew")
	(generator_version "10.0")
	(general
		(thickness 1.6)
		(legacy_teardrops no)
	)
	(paper "A4")
	(title_block
		(title "04192023_DAF0TMB3IC0_F0TG_MB_C_brd_V02_OCP.brd")
		(comment 1 "Grand Teton / footprints 2431-2432 of 8354")
	)
	(layers
		(0 "F.Cu" signal "TOP")
		(4 "In1.Cu" signal "GND")
		(6 "In2.Cu" signal "IN1")
		(8 "In3.Cu" signal "GND1")
		(10 "In4.Cu" signal "IN2")
		(12 "In5.Cu" signal "GND2")
		(14 "In6.Cu" signal "IN3")
		(16 "In7.Cu" signal "GND3")
		(18 "In8.Cu" signal "VCC")
		(20 "In9.Cu" signal "VCC1")
		(22 "In10.Cu" signal "GND4")
		(24 "In11.Cu" signal "IN4")
		(26 "In12.Cu" signal "GND5")
		(28 "In13.Cu" signal "IN5")
		(30 "In14.Cu" signal "GND6")
		(32 "In15.Cu" signal "IN6")
		(34 "In16.Cu" signal "GND7")
		(2 "B.Cu" signal "BOTTOM")
		(9 "F.Adhes" user "F.Adhesive")
		(11 "B.Adhes" user "B.Adhesive")
		(13 "F.Paste" user "Package Geometry/Pastemask Top")
		(15 "B.Paste" user "Package Geometry/Pastemask Bottom")
		(5 "F.SilkS" user "Ref Des/Silkscreen Top")
		(7 "B.SilkS" user "Ref Des/Silkscreen Bottom")
		(1 "F.Mask" user "Board Geometry/Soldermask Top")
		(3 "B.Mask" user "Board Geometry/Soldermask Bottom")
		(17 "Dwgs.User" user "User.Drawings")
		(19 "Cmts.User" user "User.Comments")
		(21 "Eco1.User" user "User.Eco1")
		(23 "Eco2.User" user "User.Eco2")
		(25 "Edge.Cuts" user "Board Geometry/Outline")
		(27 "Margin" user)
		(31 "F.CrtYd" user "Package Geometry/Place Bound Top")
		(29 "B.CrtYd" user "Package Geometry/Place Bound Bottom")
		(35 "F.Fab" user "Ref Des/Assembly Top")
		(33 "B.Fab" user "Ref Des/Assembly Bottom")
	)
	(footprint ""
		(layer "F.Cu")
		(at 208.878932 -119.721376)
		(property "Reference" "R2664"
			(at 0 0 0)
			(layer "F.SilkS")
			(hide yes)
			(effects
				(font
					(size 1.27 1.27)
				)
			)
		)
		(property "Value" ""
			(at 0 0 0)
			(layer "F.Fab")
			(effects
				(font
					(size 1.27 1.27)
				)
			)
		)
		(duplicate_pad_numbers_are_jumpers no)
		(fp_line
			(start -0.7874 -0.4064)
			(end 0.7874 -0.4064)
			(stroke
				(width 0.1524)
				(type default)
			)
			(layer "F.SilkS")
		)
		(fp_line
			(start -0.7874 0.4064)
			(end -0.7874 -0.4064)
			(stroke
				(width 0.1524)
				(type default)
			)
			(layer "F.SilkS")
		)
		(fp_line
			(start 0.7874 -0.4064)
			(end 0.7874 0.4064)
			(stroke
				(width 0.1524)
				(type default)
			)
			(layer "F.SilkS")
		)
		(fp_line
			(start 0.7874 0.4064)
			(end -0.7874 0.4064)
			(stroke
				(width 0.1524)
				(type default)
			)
			(layer "F.SilkS")
		)
		(fp_line
			(start -0.67945 -0.305054)
			(end -0.12065 -0.305054)
			(stroke
				(width 0.1)
				(type default)
			)
			(layer "F.Fab")
		)
		(fp_line
			(start -0.67945 0.3048)
			(end -0.67945 -0.305054)
			(stroke
				(width 0.1)
				(type default)
			)
			(layer "F.Fab")
		)
		(fp_line
			(start -0.12065 -0.305054)
			(end -0.12065 -0.2794)
			(stroke
				(width 0.1)
				(type default)
			)
			(layer "F.Fab")
		)
		(fp_line
			(start -0.12065 -0.2794)
			(end 0.12065 -0.2794)
			(stroke
				(width 0.1)
				(type default)
			)
			(layer "F.Fab")
		)
		(fp_line
			(start -0.12065 0.2794)
			(end -0.12065 0.3048)
			(stroke
				(width 0.1)
				(type default)
			)
			(layer "F.Fab")
		)
		(fp_line
			(start -0.12065 0.3048)
			(end -0.67945 0.3048)
			(stroke
				(width 0.1)
				(type default)
			)
			(layer "F.Fab")
		)
		(fp_line
			(start 0.120396 0.2794)
			(end -0.12065 0.2794)
			(stroke
				(width 0.1)
				(type default)
			)
			(layer "F.Fab")
		)
		(fp_line
			(start 0.120396 0.3048)
			(end 0.120396 0.2794)
			(stroke
				(width 0.1)
				(type default)
			)
			(layer "F.Fab")
		)
		(fp_line
			(start 0.12065 -0.3048)
			(end 0.67945 -0.3048)
			(stroke
				(width 0.1)
				(type default)
			)
			(layer "F.Fab")
		)
		(fp_line
			(start 0.12065 -0.2794)
			(end 0.12065 -0.3048)
			(stroke
				(width 0.1)
				(type default)
			)
			(layer "F.Fab")
		)
		(fp_line
			(start 0.67945 -0.3048)
			(end 0.67945 0.3048)
			(stroke
				(width 0.1)
				(type default)
			)
			(layer "F.Fab")
		)
		(fp_line
			(start 0.67945 0.3048)
			(end 0.120396 0.3048)
			(stroke
				(width 0.1)
				(type default)
			)
			(layer "F.Fab")
		)
		(pad "1" smd circle
			(at -0.40005 0)
			(size 0 0)
			(layers "F.Cu" "F.Mask" "F.Paste")
			(net "FM_GPU_PWRGD_ISO_R")
		)
		(pad "2" smd circle
			(at 0.40005 0)
			(size 0 0)
			(layers "F.Cu" "F.Mask" "F.Paste")
			(net "FM_GPU_PWRGD_ISO")
		)
	)
	(footprint ""
		(layer "F.Cu")
		(at 279.513792 -115.66017 180)
		(property "Reference" "R2967"
			(at 0 0 180)
			(layer "F.SilkS")
			(hide yes)
			(effects
				(font
					(size 1.27 1.27)
				)
			)
		)
		(property "Value" ""
			(at 0 0 180)
			(layer "F.Fab")
			(effects
				(font
					(size 1.27 1.27)
				)
			)
		)
		(duplicate_pad_numbers_are_jumpers no)
		(fp_line
			(start 0.7874 0.4064)
			(end -0.7874 0.4064)
			(stroke
				(width 0.1524)
				(type default)
			)
			(layer "F.SilkS")
		)
		(fp_line
			(start 0.7874 -0.4064)
			(end 0.7874 0.4064)
			(stroke
				(width 0.1524)
				(type default)
			)
			(layer "F.SilkS")
		)
		(fp_line
			(start -0.7874 0.4064)
			(end -0.7874 -0.4064)
			(stroke
				(width 0.1524)
				(type default)
			)
			(layer "F.SilkS")
		)
		(fp_line
			(start -0.7874 -0.4064)
			(end 0.7874 -0.4064)
			(stroke
				(width 0.1524)
				(type default)
			)
			(layer "F.SilkS")
		)
		(fp_line
			(start 0.67945 0.3048)
			(end 0.120396 0.3048)
			(stroke
				(width 0.1)
				(type default)
			)
			(layer "F.Fab")
		)
		(fp_line
			(start 0.67945 -0.3048)
			(end 0.67945 0.3048)
			(stroke
				(width 0.1)
				(type default)
			)
			(layer "F.Fab")
		)
		(fp_line
			(start 0.12065 -0.2794)
			(end 0.12065 -0.3048)
			(stroke
				(width 0.1)
				(type default)
			)
			(layer "F.Fab")
		)
		(fp_line
			(start 0.12065 -0.3048)
			(end 0.67945 -0.3048)
			(stroke
				(width 0.1)
				(type default)
			)
			(layer "F.Fab")
		)
		(fp_line
			(start 0.120396 0.3048)
			(end 0.120396 0.2794)
			(stroke
				(width 0.1)
				(type default)
			)
			(layer "F.Fab")
		)
		(fp_line
			(start 0.120396 0.2794)
			(end -0.12065 0.2794)
			(stroke
				(width 0.1)
				(type default)
			)
			(layer "F.Fab")
		)
		(fp_line
			(start -0.12065 0.3048)
			(end -0.67945 0.3048)
			(stroke
				(width 0.1)
				(type default)
			)
			(layer "F.Fab")
		)
		(fp_line
			(start -0.12065 0.2794)
			(end -0.12065 0.3048)
			(stroke
				(width 0.1)
				(type default)
			)
			(layer "F.Fab")
		)
		(fp_line
			(start -0.12065 -0.2794)
			(end 0.12065 -0.2794)
			(stroke
				(width 0.1)
				(type default)
			)
			(layer "F.Fab")
		)
		(fp_line
			(start -0.12065 -0.305054)
			(end -0.12065 -0.2794)
			(stroke
				(width 0.1)
				(type default)
			)
			(layer "F.Fab")
		)
		(fp_line
			(start -0.67945 0.3048)
			(end -0.67945 -0.305054)
			(stroke
				(width 0.1)
				(type default)
			)
			(layer "F.Fab")
		)
		(fp_line
			(start -0.67945 -0.305054)
			(end -0.12065 -0.305054)
			(stroke
				(width 0.1)
				(type default)
			)
			(layer "F.Fab")
		)
		(pad "1" smd circle
			(at -0.40005 0 180)
			(size 0 0)
			(layers "F.Cu" "F.Mask" "F.Paste")
			(net "SMB_PCIE0_3V3AUX_SCL_R3")
		)
		(pad "2" smd circle
			(at 0.40005 0 180)
			(size 0 0)
			(layers "F.Cu" "F.Mask" "F.Paste")
			(net "SMB_SENSOR_M2_P1_3V3AUX_SCL")
		)
	)
)
